(kicad_pcb
	(version 20260206)
	(generator "pcbnew")
	(generator_version "10.0")
	(general
		(thickness 1.6)
		(legacy_teardrops no)
	)
	(paper "A4")
	(title_block
		(title "01162023_DA0F0TEBIF0_F0T_Expander_BD_F_brd_V02_OCP.brd")
		(comment 1 "Grand Teton / footprints 624-629 of 9728")
	)
	(layers
		(0 "F.Cu" signal "TOP")
		(4 "In1.Cu" signal "GND")
		(6 "In2.Cu" signal "VCC")
		(8 "In3.Cu" signal "VCC1")
		(10 "In4.Cu" signal "GND1")
		(12 "In5.Cu" signal "IN1")
		(14 "In6.Cu" signal "GND2")
		(16 "In7.Cu" signal "IN2")
		(18 "In8.Cu" signal "GND3")
		(20 "In9.Cu" signal "IN3")
		(22 "In10.Cu" signal "GND4")
		(24 "In11.Cu" signal "IN4")
		(26 "In12.Cu" signal "GND5")
		(28 "In13.Cu" signal "IN5")
		(30 "In14.Cu" signal "GND6")
		(32 "In15.Cu" signal "IN6")
		(34 "In16.Cu" signal "GND7")
		(2 "B.Cu" signal "BOTTOM")
		(9 "F.Adhes" user "F.Adhesive")
		(11 "B.Adhes" user "B.Adhesive")
		(13 "F.Paste" user "Package Geometry/Pastemask Top")
		(15 "B.Paste" user "Package Geometry/Pastemask Bottom")
		(5 "F.SilkS" user "Ref Des/Silkscreen Top")
		(7 "B.SilkS" user "Ref Des/Silkscreen Bottom")
		(1 "F.Mask" user "Board Geometry/Soldermask Top")
		(3 "B.Mask" user "Board Geometry/Soldermask Bottom")
		(17 "Dwgs.User" user "User.Drawings")
		(19 "Cmts.User" user "User.Comments")
		(21 "Eco1.User" user "User.Eco1")
		(23 "Eco2.User" user "User.Eco2")
		(25 "Edge.Cuts" user "Board Geometry/Outline")
		(27 "Margin" user)
		(31 "F.CrtYd" user "Package Geometry/Place Bound Top")
		(29 "B.CrtYd" user "Package Geometry/Place Bound Bottom")
		(35 "F.Fab" user "Ref Des/Assembly Top")
		(33 "B.Fab" user "Ref Des/Assembly Bottom")
	)
	(footprint ""
		(layer "F.Cu")
		(at 133.594856 -170.599862 90)
		(property "Reference" "R1094"
			(at 0 0 90)
			(layer "F.SilkS")
			(hide yes)
			(effects
				(font
					(size 1.27 1.27)
				)
			)
		)
		(property "Value" ""
			(at 0 0 90)
			(layer "F.Fab")
			(effects
				(font
					(size 1.27 1.27)
				)
			)
		)
		(duplicate_pad_numbers_are_jumpers no)
		(fp_line
			(start -0.7874 -0.4064)
			(end 0.7874 -0.4064)
			(stroke
				(width 0.1524)
				(type default)
			)
			(layer "F.SilkS")
		)
		(fp_line
			(start -0.12065 -0.305054)
			(end -0.12065 -0.2794)
			(stroke
				(width 0.1)
				(type default)
			)
			(layer "F.Fab")
		)
		(fp_line
			(start -0.67945 -0.305054)
			(end -0.12065 -0.305054)
			(stroke
				(width 0.1)
				(type default)
			)
			(layer "F.Fab")
		)
		(fp_line
			(start 0.67945 -0.3048)
			(end 0.67945 0.3048)
			(stroke
				(width 0.1)
				(type default)
			)
			(layer "F.Fab")
		)
		(fp_line
			(start 0.12065 -0.3048)
			(end 0.67945 -0.3048)
			(stroke
				(width 0.1)
				(type default)
			)
			(layer "F.Fab")
		)
		(fp_line
			(start 0.12065 -0.2794)
			(end 0.12065 -0.3048)
			(stroke
				(width 0.1)
				(type default)
			)
			(layer "F.Fab")
		)
		(fp_line
			(start -0.12065 -0.2794)
			(end 0.12065 -0.2794)
			(stroke
				(width 0.1)
				(type default)
			)
			(layer "F.Fab")
		)
		(fp_line
			(start 0.120396 0.2794)
			(end -0.12065 0.2794)
			(stroke
				(width 0.1)
				(type default)
			)
			(layer "F.Fab")
		)
		(fp_line
			(start -0.12065 0.2794)
			(end -0.12065 0.3048)
			(stroke
				(width 0.1)
				(type default)
			)
			(layer "F.Fab")
		)
		(fp_line
			(start 0.67945 0.3048)
			(end 0.120396 0.3048)
			(stroke
				(width 0.1)
				(type default)
			)
			(layer "F.Fab")
		)
		(fp_line
			(start 0.120396 0.3048)
			(end 0.120396 0.2794)
			(stroke
				(width 0.1)
				(type default)
			)
			(layer "F.Fab")
		)
		(fp_line
			(start -0.12065 0.3048)
			(end -0.67945 0.3048)
			(stroke
				(width 0.1)
				(type default)
			)
			(layer "F.Fab")
		)
		(fp_line
			(start -0.67945 0.3048)
			(end -0.67945 -0.305054)
			(stroke
				(width 0.1)
				(type default)
			)
			(layer "F.Fab")
		)
		(pad "1" smd circle
			(at -0.40005 0 90)
			(size 0 0)
			(layers "F.Cu" "F.Mask" "F.Paste")
			(net "CLK_100M_DB2000QL_NIC0_R_DP")
		)
		(pad "2" smd circle
			(at 0.40005 0 90)
			(size 0 0)
			(layers "F.Cu" "F.Mask" "F.Paste")
			(net "CLK_100M_DB2000QL_NIC0_DP")
		)
	)
	(footprint ""
		(layer "F.Cu")
		(at 22.416008 -343.952322 90)
		(property "Reference" "C189"
			(at 0 0 90)
			(layer "F.SilkS")
			(hide yes)
			(effects
				(font
					(size 1.27 1.27)
				)
			)
		)
		(property "Value" ""
			(at 0 0 90)
			(layer "F.Fab")
			(effects
				(font
					(size 1.27 1.27)
				)
			)
		)
		(duplicate_pad_numbers_are_jumpers no)
		(fp_line
			(start 0.299974 -0.150114)
			(end 0.299974 0.150114)
			(stroke
				(width 0.1)
				(type default)
			)
			(layer "F.Fab")
		)
		(fp_line
			(start -0.299974 -0.150114)
			(end 0.299974 -0.150114)
			(stroke
				(width 0.1)
				(type default)
			)
			(layer "F.Fab")
		)
		(fp_line
			(start 0.299974 0.150114)
			(end -0.299974 0.150114)
			(stroke
				(width 0.1)
				(type default)
			)
			(layer "F.Fab")
		)
		(fp_line
			(start -0.299974 0.150114)
			(end -0.299974 -0.150114)
			(stroke
				(width 0.1)
				(type default)
			)
			(layer "F.Fab")
		)
		(pad "1" smd rect
			(at -0.2667 0 90)
			(size 0.3048 0.381)
			(layers "F.Cu" "F.Mask" "F.Paste")
			(net "P5E_PEX0_STN7_TX_DP<113>")
		)
		(pad "2" smd rect
			(at 0.2667 0 90)
			(size 0.3048 0.381)
			(layers "F.Cu" "F.Mask" "F.Paste")
			(net "P5E_PEX0_STN7_TX_C_DP<113>")
		)
	)
	(footprint ""
		(layer "F.Cu")
		(at 198.250302 -80.581246 90)
		(property "Reference" "U27"
			(at -0.063246 2.410968 90)
			(unlocked yes)
			(layer "F.SilkS")
			(effects
				(font
					(size 0.7874 0.5842)
					(thickness 0.1524)
				)
			)
		)
		(property "Value" ""
			(at 0 0 90)
			(layer "F.Fab")
			(effects
				(font
					(size 1.27 1.27)
				)
			)
		)
		(duplicate_pad_numbers_are_jumpers no)
		(fp_line
			(start 1.905 -1.651)
			(end 1.905 1.651)
			(stroke
				(width 0.1524)
				(type default)
			)
			(layer "F.SilkS")
		)
		(fp_line
			(start -1.905 -1.651)
			(end 1.905 -1.651)
			(stroke
				(width 0.1524)
				(type default)
			)
			(layer "F.SilkS")
		)
		(fp_line
			(start 1.905 1.651)
			(end -1.905 1.651)
			(stroke
				(width 0.1524)
				(type default)
			)
			(layer "F.SilkS")
		)
		(fp_line
			(start -1.905 1.651)
			(end -1.905 -1.651)
			(stroke
				(width 0.1524)
				(type default)
			)
			(layer "F.SilkS")
		)
		(fp_line
			(start 0.6985 -1.524)
			(end 0.6985 -0.219964)
			(stroke
				(width 0.1)
				(type default)
			)
			(layer "F.Fab")
		)
		(fp_line
			(start -0.649986 -1.524)
			(end 0.6985 -1.524)
			(stroke
				(width 0.1)
				(type default)
			)
			(layer "F.Fab")
		)
		(fp_line
			(start -0.649986 -1.169924)
			(end -0.649986 -1.524)
			(stroke
				(width 0.1)
				(type default)
			)
			(layer "F.Fab")
		)
		(fp_line
			(start -1.249934 -1.169924)
			(end -0.649986 -1.169924)
			(stroke
				(width 0.1)
				(type default)
			)
			(layer "F.Fab")
		)
		(fp_line
			(start -0.6985 -0.729996)
			(end -1.249934 -0.729996)
			(stroke
				(width 0.1)
				(type default)
			)
			(layer "F.Fab")
		)
		(fp_line
			(start -1.249934 -0.729996)
			(end -1.249934 -1.169924)
			(stroke
				(width 0.1)
				(type default)
			)
			(layer "F.Fab")
		)
		(fp_line
			(start 1.249934 -0.219964)
			(end 1.249934 0.219964)
			(stroke
				(width 0.1)
				(type default)
			)
			(layer "F.Fab")
		)
		(fp_line
			(start 0.6985 -0.219964)
			(end 1.249934 -0.219964)
			(stroke
				(width 0.1)
				(type default)
			)
			(layer "F.Fab")
		)
		(fp_line
			(start 1.249934 0.219964)
			(end 0.6985 0.219964)
			(stroke
				(width 0.1)
				(type default)
			)
			(layer "F.Fab")
		)
		(fp_line
			(start 0.6985 0.219964)
			(end 0.6985 1.524)
			(stroke
				(width 0.1)
				(type default)
			)
			(layer "F.Fab")
		)
		(fp_line
			(start -0.6985 0.729996)
			(end -0.6985 -0.729996)
			(stroke
				(width 0.1)
				(type default)
			)
			(layer "F.Fab")
		)
		(fp_line
			(start -1.249934 0.729996)
			(end -0.6985 0.729996)
			(stroke
				(width 0.1)
				(type default)
			)
			(layer "F.Fab")
		)
		(fp_line
			(start -0.649986 1.169924)
			(end -1.249934 1.169924)
			(stroke
				(width 0.1)
				(type default)
			)
			(layer "F.Fab")
		)
		(fp_line
			(start -1.249934 1.169924)
			(end -1.249934 0.729996)
			(stroke
				(width 0.1)
				(type default)
			)
			(layer "F.Fab")
		)
		(fp_line
			(start 0.6985 1.524)
			(end -0.649986 1.524)
			(stroke
				(width 0.1)
				(type default)
			)
			(layer "F.Fab")
		)
		(fp_line
			(start -0.649986 1.524)
			(end -0.649986 1.169924)
			(stroke
				(width 0.1)
				(type default)
			)
			(layer "F.Fab")
		)
		(pad "1" smd rect
			(at -1.1176 -1.016)
			(size 1.016 1.27)
			(layers "F.Cu" "F.Mask" "F.Paste")
			(net "HP_NIC3_PWRGD")
		)
		(pad "2" smd rect
			(at -1.1176 1.016)
			(size 1.016 1.27)
			(layers "F.Cu" "F.Mask" "F.Paste")
			(net "P3V3_NIC3")
		)
		(pad "3" smd rect
			(at 1.1176 0)
			(size 1.016 1.27)
			(layers "F.Cu" "F.Mask" "F.Paste")
			(net "GND")
		)
	)
	(footprint ""
		(layer "F.Cu")
		(at 277.938484 -44.341542 90)
		(property "Reference" "C326"
			(at 0 0 90)
			(layer "F.SilkS")
			(hide yes)
			(effects
				(font
					(size 1.27 1.27)
				)
			)
		)
		(property "Value" ""
			(at 0 0 90)
			(layer "F.Fab")
			(effects
				(font
					(size 1.27 1.27)
				)
			)
		)
		(duplicate_pad_numbers_are_jumpers no)
		(fp_line
			(start 0.7874 -0.4064)
			(end 0.7874 0.4064)
			(stroke
				(width 0.1524)
				(type default)
			)
			(layer "F.SilkS")
		)
		(fp_line
			(start -0.7874 -0.4064)
			(end 0.7874 -0.4064)
			(stroke
				(width 0.1524)
				(type default)
			)
			(layer "F.SilkS")
		)
		(fp_line
			(start 0.7874 0.4064)
			(end -0.7874 0.4064)
			(stroke
				(width 0.1524)
				(type default)
			)
			(layer "F.SilkS")
		)
		(fp_line
			(start -0.7874 0.4064)
			(end -0.7874 -0.4064)
			(stroke
				(width 0.1524)
				(type default)
			)
			(layer "F.SilkS")
		)
		(fp_line
			(start -0.12065 -0.305054)
			(end -0.12065 -0.2794)
			(stroke
				(width 0.1)
				(type default)
			)
			(layer "F.Fab")
		)
		(fp_line
			(start -0.67945 -0.305054)
			(end -0.12065 -0.305054)
			(stroke
				(width 0.1)
				(type default)
			)
			(layer "F.Fab")
		)
		(fp_line
			(start 0.67945 -0.3048)
			(end 0.67945 0.3048)
			(stroke
				(width 0.1)
				(type default)
			)
			(layer "F.Fab")
		)
		(fp_line
			(start 0.12065 -0.3048)
			(end 0.67945 -0.3048)
			(stroke
				(width 0.1)
				(type default)
			)
			(layer "F.Fab")
		)
		(fp_line
			(start 0.12065 -0.2794)
			(end 0.12065 -0.3048)
			(stroke
				(width 0.1)
				(type default)
			)
			(layer "F.Fab")
		)
		(fp_line
			(start -0.12065 -0.2794)
			(end 0.12065 -0.2794)
			(stroke
				(width 0.1)
				(type default)
			)
			(layer "F.Fab")
		)
		(fp_line
			(start 0.120396 0.2794)
			(end -0.12065 0.2794)
			(stroke
				(width 0.1)
				(type default)
			)
			(layer "F.Fab")
		)
		(fp_line
			(start -0.12065 0.2794)
			(end -0.12065 0.3048)
			(stroke
				(width 0.1)
				(type default)
			)
			(layer "F.Fab")
		)
		(fp_line
			(start 0.67945 0.3048)
			(end 0.120396 0.3048)
			(stroke
				(width 0.1)
				(type default)
			)
			(layer "F.Fab")
		)
		(fp_line
			(start 0.120396 0.3048)
			(end 0.120396 0.2794)
			(stroke
				(width 0.1)
				(type default)
			)
			(layer "F.Fab")
		)
		(fp_line
			(start -0.12065 0.3048)
			(end -0.67945 0.3048)
			(stroke
				(width 0.1)
				(type default)
			)
			(layer "F.Fab")
		)
		(fp_line
			(start -0.67945 0.3048)
			(end -0.67945 -0.305054)
			(stroke
				(width 0.1)
				(type default)
			)
			(layer "F.Fab")
		)
		(pad "1" smd circle
			(at -0.40005 0 90)
			(size 0 0)
			(layers "F.Cu" "F.Mask" "F.Paste")
			(net "P12V_SSD9_VIN_P")
		)
		(pad "2" smd circle
			(at 0.40005 0 90)
			(size 0 0)
			(layers "F.Cu" "F.Mask" "F.Paste")
			(net "P12V_SSD9_VIN_N")
		)
	)
	(footprint ""
		(layer "F.Cu")
		(at 40.598344 -250.070874 -90)
		(property "Reference" "R1153"
			(at 0 0 270)
			(layer "F.SilkS")
			(hide yes)
			(effects
				(font
					(size 1.27 1.27)
				)
			)
		)
		(property "Value" ""
			(at 0 0 270)
			(layer "F.Fab")
			(effects
				(font
					(size 1.27 1.27)
				)
			)
		)
		(duplicate_pad_numbers_are_jumpers no)
		(fp_line
			(start -0.7874 0.4064)
			(end -0.7874 -0.4064)
			(stroke
				(width 0.1524)
				(type default)
			)
			(layer "F.SilkS")
		)
		(fp_line
			(start 0.7874 0.4064)
			(end -0.7874 0.4064)
			(stroke
				(width 0.1524)
				(type default)
			)
			(layer "F.SilkS")
		)
		(fp_line
			(start -0.7874 -0.4064)
			(end 0.7874 -0.4064)
			(stroke
				(width 0.1524)
				(type default)
			)
			(layer "F.SilkS")
		)
		(fp_line
			(start 0.7874 -0.4064)
			(end 0.7874 0.4064)
			(stroke
				(width 0.1524)
				(type default)
			)
			(layer "F.SilkS")
		)
		(fp_line
			(start -0.67945 0.3048)
			(end -0.67945 -0.305054)
			(stroke
				(width 0.1)
				(type default)
			)
			(layer "F.Fab")
		)
		(fp_line
			(start -0.12065 0.3048)
			(end -0.67945 0.3048)
			(stroke
				(width 0.1)
				(type default)
			)
			(layer "F.Fab")
		)
		(fp_line
			(start 0.120396 0.3048)
			(end 0.120396 0.2794)
			(stroke
				(width 0.1)
				(type default)
			)
			(layer "F.Fab")
		)
		(fp_line
			(start 0.67945 0.3048)
			(end 0.120396 0.3048)
			(stroke
				(width 0.1)
				(type default)
			)
			(layer "F.Fab")
		)
		(fp_line
			(start -0.12065 0.2794)
			(end -0.12065 0.3048)
			(stroke
				(width 0.1)
				(type default)
			)
			(layer "F.Fab")
		)
		(fp_line
			(start 0.120396 0.2794)
			(end -0.12065 0.2794)
			(stroke
				(width 0.1)
				(type default)
			)
			(layer "F.Fab")
		)
		(fp_line
			(start -0.12065 -0.2794)
			(end 0.12065 -0.2794)
			(stroke
				(width 0.1)
				(type default)
			)
			(layer "F.Fab")
		)
		(fp_line
			(start 0.12065 -0.2794)
			(end 0.12065 -0.3048)
			(stroke
				(width 0.1)
				(type default)
			)
			(layer "F.Fab")
		)
		(fp_line
			(start 0.12065 -0.3048)
			(end 0.67945 -0.3048)
			(stroke
				(width 0.1)
				(type default)
			)
			(layer "F.Fab")
		)
		(fp_line
			(start 0.67945 -0.3048)
			(end 0.67945 0.3048)
			(stroke
				(width 0.1)
				(type default)
			)
			(layer "F.Fab")
		)
		(fp_line
			(start -0.67945 -0.305054)
			(end -0.12065 -0.305054)
			(stroke
				(width 0.1)
				(type default)
			)
			(layer "F.Fab")
		)
		(fp_line
			(start -0.12065 -0.305054)
			(end -0.12065 -0.2794)
			(stroke
				(width 0.1)
				(type default)
			)
			(layer "F.Fab")
		)
		(pad "1" smd circle
			(at -0.40005 0 270)
			(size 0 0)
			(layers "F.Cu" "F.Mask" "F.Paste")
			(net "PEX0_MODE_SEL1")
		)
		(pad "2" smd circle
			(at 0.40005 0 270)
			(size 0 0)
			(layers "F.Cu" "F.Mask" "F.Paste")
			(net "P1V8_PEX")
		)
	)
	(footprint ""
		(layer "F.Cu")
		(at 8.110474 -63.652146 180)
		(property "Reference" "R5840"
			(at 0 0 180)
			(layer "F.SilkS")
			(hide yes)
			(effects
				(font
					(size 1.27 1.27)
				)
			)
		)
		(property "Value" ""
			(at 0 0 180)
			(layer "F.Fab")
			(effects
				(font
					(size 1.27 1.27)
				)
			)
		)
		(duplicate_pad_numbers_are_jumpers no)
		(fp_line
			(start 0.7874 0.4064)
			(end -0.7874 0.4064)
			(stroke
				(width 0.1524)
				(type default)
			)
			(layer "F.SilkS")
		)
		(fp_line
			(start 0.7874 -0.4064)
			(end 0.7874 0.4064)
			(stroke
				(width 0.1524)
				(type default)
			)
			(layer "F.SilkS")
		)
		(fp_line
			(start -0.7874 0.4064)
			(end -0.7874 -0.4064)
			(stroke
				(width 0.1524)
				(type default)
			)
			(layer "F.SilkS")
		)
		(fp_line
			(start -0.7874 -0.4064)
			(end 0.7874 -0.4064)
			(stroke
				(width 0.1524)
				(type default)
			)
			(layer "F.SilkS")
		)
		(fp_line
			(start 0.67945 0.3048)
			(end 0.120396 0.3048)
			(stroke
				(width 0.1)
				(type default)
			)
			(layer "F.Fab")
		)
		(fp_line
			(start 0.67945 -0.3048)
			(end 0.67945 0.3048)
			(stroke
				(width 0.1)
				(type default)
			)
			(layer "F.Fab")
		)
		(fp_line
			(start 0.12065 -0.2794)
			(end 0.12065 -0.3048)
			(stroke
				(width 0.1)
				(type default)
			)
			(layer "F.Fab")
		)
		(fp_line
			(start 0.12065 -0.3048)
			(end 0.67945 -0.3048)
			(stroke
				(width 0.1)
				(type default)
			)
			(layer "F.Fab")
		)
		(fp_line
			(start 0.120396 0.3048)
			(end 0.120396 0.2794)
			(stroke
				(width 0.1)
				(type default)
			)
			(layer "F.Fab")
		)
		(fp_line
			(start 0.120396 0.2794)
			(end -0.12065 0.2794)
			(stroke
				(width 0.1)
				(type default)
			)
			(layer "F.Fab")
		)
		(fp_line
			(start -0.12065 0.3048)
			(end -0.67945 0.3048)
			(stroke
				(width 0.1)
				(type default)
			)
			(layer "F.Fab")
		)
		(fp_line
			(start -0.12065 0.2794)
			(end -0.12065 0.3048)
			(stroke
				(width 0.1)
				(type default)
			)
			(layer "F.Fab")
		)
		(fp_line
			(start -0.12065 -0.2794)
			(end 0.12065 -0.2794)
			(stroke
				(width 0.1)
				(type default)
			)
			(layer "F.Fab")
		)
		(fp_line
			(start -0.12065 -0.305054)
			(end -0.12065 -0.2794)
			(stroke
				(width 0.1)
				(type default)
			)
			(layer "F.Fab")
		)
		(fp_line
			(start -0.67945 0.3048)
			(end -0.67945 -0.305054)
			(stroke
				(width 0.1)
				(type default)
			)
			(layer "F.Fab")
		)
		(fp_line
			(start -0.67945 -0.305054)
			(end -0.12065 -0.305054)
			(stroke
				(width 0.1)
				(type default)
			)
			(layer "F.Fab")
		)
		(pad "1" smd circle
			(at -0.40005 0 180)
			(size 0 0)
			(layers "F.Cu" "F.Mask" "F.Paste")
			(net "P5V_AUX")
		)
		(pad "2" smd circle
			(at 0.40005 0 180)
			(size 0 0)
			(layers "F.Cu" "F.Mask" "F.Paste")
			(net "P12V_SSD0_PG_G2")
		)
	)
)
